(kicad_pcb
	(version 20260206)
	(generator "pcbnew")
	(generator_version "10.0")
	(general
		(thickness 1.6)
		(legacy_teardrops no)
	)
	(paper "A4")
	(title_block
		(title "Bryce Canyon_SCC_16316-1_OCP.brd")
		(comment 1 "Bryce Canyon / footprints 429-435 of 1561")
	)
	(layers
		(0 "F.Cu" signal "TOP")
		(4 "In1.Cu" signal "L2GND")
		(6 "In2.Cu" signal "L3")
		(8 "In3.Cu" signal "L4VCC")
		(10 "In4.Cu" signal "L5VCC")
		(12 "In5.Cu" signal "L6")
		(14 "In6.Cu" signal "L7GND")
		(2 "B.Cu" signal "BOTTOM")
		(9 "F.Adhes" user "F.Adhesive")
		(11 "B.Adhes" user "B.Adhesive")
		(13 "F.Paste" user "Package Geometry/Pastemask Top")
		(15 "B.Paste" user "Package Geometry/Pastemask Bottom")
		(5 "F.SilkS" user "Ref Des/Silkscreen Top")
		(7 "B.SilkS" user "Ref Des/Silkscreen Bottom")
		(1 "F.Mask" user "Board Geometry/Soldermask Top")
		(3 "B.Mask" user "Board Geometry/Soldermask Bottom")
		(17 "Dwgs.User" user "User.Drawings")
		(19 "Cmts.User" user "User.Comments")
		(21 "Eco1.User" user "User.Eco1")
		(23 "Eco2.User" user "User.Eco2")
		(25 "Edge.Cuts" user "Board Geometry/Outline")
		(27 "Margin" user)
		(31 "F.CrtYd" user "Package Geometry/Place Bound Top")
		(29 "B.CrtYd" user "Package Geometry/Place Bound Bottom")
		(35 "F.Fab" user "Ref Des/Assembly Top")
		(33 "B.Fab" user "Ref Des/Assembly Bottom")
	)
	(footprint ""
		(layer "F.Cu")
		(at 13.3096 -59.1312)
		(property "Reference" "R693"
			(at 0 0 0)
			(layer "F.SilkS")
			(hide yes)
			(effects
				(font
					(size 1.27 1.27)
				)
			)
		)
		(property "Value" "10KR2F-2-GP"
			(at 0.064008 -3.993896 0)
			(unlocked yes)
			(layer "F.Fab")
			(hide yes)
			(effects
				(font
					(size 1.016 1.016)
					(thickness 0.1524)
				)
			)
		)
		(property "Device Type" "R402H16"
			(at 0.064008 -5.517896 0)
			(unlocked yes)
			(layer "F.Fab")
			(hide yes)
			(effects
				(font
					(size 1.016 1.016)
					(thickness 0.1524)
				)
			)
		)
		(duplicate_pad_numbers_are_jumpers no)
		(fp_line
			(start -0.508 -0.9398)
			(end -0.508 0.9398)
			(stroke
				(width 0.1524)
				(type default)
			)
			(layer "F.SilkS")
		)
		(fp_line
			(start 0.508 -0.9398)
			(end -0.508 -0.9398)
			(stroke
				(width 0.1524)
				(type default)
			)
			(layer "F.SilkS")
		)
		(fp_rect
			(start -0.508 0.9398)
			(end 0.508 -0.9398)
			(stroke
				(width 0)
				(type default)
			)
			(fill no)
			(layer "F.CrtYd")
		)
		(fp_rect
			(start -0.508 0.9398)
			(end 0.508 -0.9398)
			(stroke
				(width 0)
				(type default)
			)
			(fill no)
			(layer "F.Fab")
		)
		(pad "1" smd custom
			(at 0 -0.4445)
			(size 0.1397 0.1397)
			(layers "F.Cu" "F.Mask" "F.Paste")
			(net "GND")
			(options
				(clearance outline)
				(anchor circle)
			)
			(primitives
				(gr_poly
					(pts
						(arc
							(start -0.1778 -0.2794)
							(mid -0.249642 -0.249642)
							(end -0.2794 -0.1778)
						)
						(arc
							(start -0.2794 0.1778)
							(mid -0.249642 0.249642)
							(end -0.1778 0.2794)
						)
						(arc
							(start 0.1778 0.2794)
							(mid 0.249642 0.249642)
							(end 0.2794 0.1778)
						)
						(arc
							(start 0.2794 -0.1778)
							(mid 0.249642 -0.249642)
							(end 0.1778 -0.2794)
						)
					)
					(width 0)
					(fill yes)
				)
			)
		)
		(pad "2" smd custom
			(at 0 0.4445)
			(size 0.1397 0.1397)
			(layers "F.Cu" "F.Mask" "F.Paste")
			(net "MB0_HS_ENABLE")
			(options
				(clearance outline)
				(anchor circle)
			)
			(primitives
				(gr_poly
					(pts
						(arc
							(start -0.1778 -0.2794)
							(mid -0.249642 -0.249642)
							(end -0.2794 -0.1778)
						)
						(arc
							(start -0.2794 0.1778)
							(mid -0.249642 0.249642)
							(end -0.1778 0.2794)
						)
						(arc
							(start 0.1778 0.2794)
							(mid 0.249642 0.249642)
							(end 0.2794 0.1778)
						)
						(arc
							(start 0.2794 -0.1778)
							(mid 0.249642 -0.249642)
							(end 0.1778 -0.2794)
						)
					)
					(width 0)
					(fill yes)
				)
			)
		)
	)
	(footprint ""
		(layer "F.Cu")
		(at 75.438 -41.148 180)
		(property "Reference" "C288"
			(at 0 0 180)
			(layer "F.SilkS")
			(hide yes)
			(effects
				(font
					(size 1.27 1.27)
				)
			)
		)
		(property "Value" "SC22U6D3V3MX-9-GP-U"
			(at 0 -2.8194 180)
			(unlocked yes)
			(layer "F.Fab")
			(hide yes)
			(effects
				(font
					(size 1.016 1.016)
					(thickness 0.1524)
				)
			)
		)
		(property "Device Type" "C603H40"
			(at 0 -4.3434 180)
			(unlocked yes)
			(layer "F.Fab")
			(hide yes)
			(effects
				(font
					(size 1.016 1.016)
					(thickness 0.1524)
				)
			)
		)
		(duplicate_pad_numbers_are_jumpers no)
		(fp_line
			(start 0.508 0)
			(end -0.508 0)
			(stroke
				(width 0.2032)
				(type default)
			)
			(layer "F.SilkS")
		)
		(fp_rect
			(start -0.5842 1.3335)
			(end 0.5842 -1.3335)
			(stroke
				(width 0)
				(type default)
			)
			(fill no)
			(layer "F.CrtYd")
		)
		(fp_rect
			(start -0.5842 1.3335)
			(end 0.5842 -1.3335)
			(stroke
				(width 0)
				(type default)
			)
			(fill no)
			(layer "F.Fab")
		)
		(pad "1" smd custom
			(at 0 -0.762 180)
			(size 0.2159 0.2159)
			(layers "F.Cu" "F.Mask" "F.Paste")
			(net "GB_VDDA")
			(options
				(clearance outline)
				(anchor circle)
			)
			(primitives
				(gr_poly
					(pts
						(arc
							(start -0.3302 -0.4318)
							(mid -0.402042 -0.402042)
							(end -0.4318 -0.3302)
						)
						(arc
							(start -0.4318 0.3302)
							(mid -0.402042 0.402042)
							(end -0.3302 0.4318)
						)
						(arc
							(start 0.3302 0.4318)
							(mid 0.402042 0.402042)
							(end 0.4318 0.3302)
						)
						(arc
							(start 0.4318 -0.3302)
							(mid 0.402042 -0.402042)
							(end 0.3302 -0.4318)
						)
					)
					(width 0)
					(fill yes)
				)
			)
		)
		(pad "2" smd custom
			(at 0 0.762 180)
			(size 0.2159 0.2159)
			(layers "F.Cu" "F.Mask" "F.Paste")
			(net "GND")
			(options
				(clearance outline)
				(anchor circle)
			)
			(primitives
				(gr_poly
					(pts
						(arc
							(start -0.3302 -0.4318)
							(mid -0.402042 -0.402042)
							(end -0.4318 -0.3302)
						)
						(arc
							(start -0.4318 0.3302)
							(mid -0.402042 0.402042)
							(end -0.3302 0.4318)
						)
						(arc
							(start 0.3302 0.4318)
							(mid 0.402042 0.402042)
							(end 0.4318 0.3302)
						)
						(arc
							(start 0.4318 -0.3302)
							(mid 0.402042 -0.402042)
							(end 0.3302 -0.4318)
						)
					)
					(width 0)
					(fill yes)
				)
			)
		)
	)
	(footprint ""
		(layer "F.Cu")
		(at 60.67552 -17.414748 180)
		(property "Reference" "R575"
			(at 0 0 180)
			(layer "F.SilkS")
			(hide yes)
			(effects
				(font
					(size 1.27 1.27)
				)
			)
		)
		(property "Value" "10KR2F-2-GP"
			(at 0.064008 -3.993896 180)
			(unlocked yes)
			(layer "F.Fab")
			(hide yes)
			(effects
				(font
					(size 1.016 1.016)
					(thickness 0.1524)
				)
			)
		)
		(property "Device Type" "R402H16"
			(at 0.064008 -5.517896 180)
			(unlocked yes)
			(layer "F.Fab")
			(hide yes)
			(effects
				(font
					(size 1.016 1.016)
					(thickness 0.1524)
				)
			)
		)
		(duplicate_pad_numbers_are_jumpers no)
		(fp_line
			(start 0.508 -0.9398)
			(end -0.508 -0.9398)
			(stroke
				(width 0.1524)
				(type default)
			)
			(layer "F.SilkS")
		)
		(fp_line
			(start -0.508 -0.9398)
			(end -0.508 0.9398)
			(stroke
				(width 0.1524)
				(type default)
			)
			(layer "F.SilkS")
		)
		(fp_rect
			(start -0.508 0.9398)
			(end 0.508 -0.9398)
			(stroke
				(width 0)
				(type default)
			)
			(fill no)
			(layer "F.CrtYd")
		)
		(fp_rect
			(start -0.508 0.9398)
			(end 0.508 -0.9398)
			(stroke
				(width 0)
				(type default)
			)
			(fill no)
			(layer "F.Fab")
		)
		(pad "1" smd custom
			(at 0 -0.4445 180)
			(size 0.1397 0.1397)
			(layers "F.Cu" "F.Mask" "F.Paste")
			(net "P3V3")
			(options
				(clearance outline)
				(anchor circle)
			)
			(primitives
				(gr_poly
					(pts
						(arc
							(start -0.1778 -0.2794)
							(mid -0.249642 -0.249642)
							(end -0.2794 -0.1778)
						)
						(arc
							(start -0.2794 0.1778)
							(mid -0.249642 0.249642)
							(end -0.1778 0.2794)
						)
						(arc
							(start 0.1778 0.2794)
							(mid 0.249642 0.249642)
							(end 0.2794 0.1778)
						)
						(arc
							(start 0.2794 -0.1778)
							(mid 0.249642 -0.249642)
							(end 0.1778 -0.2794)
						)
					)
					(width 0)
					(fill yes)
				)
			)
		)
		(pad "2" smd custom
			(at 0 0.4445 180)
			(size 0.1397 0.1397)
			(layers "F.Cu" "F.Mask" "F.Paste")
			(net "U49_OE")
			(options
				(clearance outline)
				(anchor circle)
			)
			(primitives
				(gr_poly
					(pts
						(arc
							(start -0.1778 -0.2794)
							(mid -0.249642 -0.249642)
							(end -0.2794 -0.1778)
						)
						(arc
							(start -0.2794 0.1778)
							(mid -0.249642 0.249642)
							(end -0.1778 0.2794)
						)
						(arc
							(start 0.1778 0.2794)
							(mid 0.249642 0.249642)
							(end 0.2794 0.1778)
						)
						(arc
							(start 0.2794 -0.1778)
							(mid 0.249642 -0.249642)
							(end 0.1778 -0.2794)
						)
					)
					(width 0)
					(fill yes)
				)
			)
		)
	)
	(footprint ""
		(layer "F.Cu")
		(at 22.1742 -57.2516 180)
		(property "Reference" "R521"
			(at 0 0 180)
			(layer "F.SilkS")
			(hide yes)
			(effects
				(font
					(size 1.27 1.27)
				)
			)
		)
		(property "Value" "38K3R2F-GP"
			(at 0.064008 -3.993896 180)
			(unlocked yes)
			(layer "F.Fab")
			(hide yes)
			(effects
				(font
					(size 1.016 1.016)
					(thickness 0.1524)
				)
			)
		)
		(property "Device Type" "R402H16"
			(at 0.064008 -5.517896 180)
			(unlocked yes)
			(layer "F.Fab")
			(hide yes)
			(effects
				(font
					(size 1.016 1.016)
					(thickness 0.1524)
				)
			)
		)
		(duplicate_pad_numbers_are_jumpers no)
		(fp_line
			(start 0.508 -0.9398)
			(end -0.508 -0.9398)
			(stroke
				(width 0.1524)
				(type default)
			)
			(layer "F.SilkS")
		)
		(fp_line
			(start -0.508 -0.9398)
			(end -0.508 0.9398)
			(stroke
				(width 0.1524)
				(type default)
			)
			(layer "F.SilkS")
		)
		(fp_rect
			(start -0.508 0.9398)
			(end 0.508 -0.9398)
			(stroke
				(width 0)
				(type default)
			)
			(fill no)
			(layer "F.CrtYd")
		)
		(fp_rect
			(start -0.508 0.9398)
			(end 0.508 -0.9398)
			(stroke
				(width 0)
				(type default)
			)
			(fill no)
			(layer "F.Fab")
		)
		(pad "1" smd custom
			(at 0 -0.4445 180)
			(size 0.1397 0.1397)
			(layers "F.Cu" "F.Mask" "F.Paste")
			(net "MB0_ISTART_R")
			(options
				(clearance outline)
				(anchor circle)
			)
			(primitives
				(gr_poly
					(pts
						(arc
							(start -0.1778 -0.2794)
							(mid -0.249642 -0.249642)
							(end -0.2794 -0.1778)
						)
						(arc
							(start -0.2794 0.1778)
							(mid -0.249642 0.249642)
							(end -0.1778 0.2794)
						)
						(arc
							(start 0.1778 0.2794)
							(mid 0.249642 0.249642)
							(end 0.2794 0.1778)
						)
						(arc
							(start 0.2794 -0.1778)
							(mid 0.249642 -0.249642)
							(end 0.1778 -0.2794)
						)
					)
					(width 0)
					(fill yes)
				)
			)
		)
		(pad "2" smd custom
			(at 0 0.4445 180)
			(size 0.1397 0.1397)
			(layers "F.Cu" "F.Mask" "F.Paste")
			(net "AGND_CURRENT_MON")
			(options
				(clearance outline)
				(anchor circle)
			)
			(primitives
				(gr_poly
					(pts
						(arc
							(start -0.1778 -0.2794)
							(mid -0.249642 -0.249642)
							(end -0.2794 -0.1778)
						)
						(arc
							(start -0.2794 0.1778)
							(mid -0.249642 0.249642)
							(end -0.1778 0.2794)
						)
						(arc
							(start 0.1778 0.2794)
							(mid 0.249642 0.249642)
							(end 0.2794 0.1778)
						)
						(arc
							(start 0.2794 -0.1778)
							(mid 0.249642 -0.249642)
							(end 0.1778 -0.2794)
						)
					)
					(width 0)
					(fill yes)
				)
			)
		)
	)
	(footprint ""
		(layer "F.Cu")
		(at 197.72376 -71.22414)
		(property "Reference" "C510"
			(at 0 0 0)
			(layer "F.SilkS")
			(hide yes)
			(effects
				(font
					(size 1.27 1.27)
				)
			)
		)
		(property "Value" "SCD1U16V2KX-3GP"
			(at 1.1811 -2.7051 0)
			(unlocked yes)
			(layer "F.Fab")
			(hide yes)
			(effects
				(font
					(size 1.016 1.016)
					(thickness 0.1524)
				)
			)
		)
		(property "Device Type" "C402H22"
			(at 1.1811 -4.2291 0)
			(unlocked yes)
			(layer "F.Fab")
			(hide yes)
			(effects
				(font
					(size 1.016 1.016)
					(thickness 0.1524)
				)
			)
		)
		(duplicate_pad_numbers_are_jumpers no)
		(fp_rect
			(start -0.4318 0.9525)
			(end 0.4318 -0.9525)
			(stroke
				(width 0)
				(type default)
			)
			(fill no)
			(layer "F.CrtYd")
		)
		(fp_rect
			(start -0.4318 0.9525)
			(end 0.4318 -0.9525)
			(stroke
				(width 0)
				(type default)
			)
			(fill no)
			(layer "F.Fab")
		)
		(pad "1" smd custom
			(at 0 -0.4445)
			(size 0.1524 0.1524)
			(layers "F.Cu" "F.Mask" "F.Paste")
			(net "P1V8_C")
			(options
				(clearance outline)
				(anchor circle)
			)
			(primitives
				(gr_poly
					(pts
						(arc
							(start 0.3048 -0.2032)
							(mid 0.275042 -0.275042)
							(end 0.2032 -0.3048)
						)
						(arc
							(start -0.2032 -0.3048)
							(mid -0.275042 -0.275042)
							(end -0.3048 -0.2032)
						)
						(arc
							(start -0.3048 0.2032)
							(mid -0.275042 0.275042)
							(end -0.2032 0.3048)
						)
						(arc
							(start 0.2032 0.3048)
							(mid 0.275042 0.275042)
							(end 0.3048 0.2032)
						)
					)
					(width 0)
					(fill yes)
				)
			)
		)
		(pad "2" smd custom
			(at 0 0.4445)
			(size 0.1524 0.1524)
			(layers "F.Cu" "F.Mask" "F.Paste")
			(net "GND")
			(options
				(clearance outline)
				(anchor circle)
			)
			(primitives
				(gr_poly
					(pts
						(arc
							(start 0.3048 -0.2032)
							(mid 0.275042 -0.275042)
							(end 0.2032 -0.3048)
						)
						(arc
							(start -0.2032 -0.3048)
							(mid -0.275042 -0.275042)
							(end -0.3048 -0.2032)
						)
						(arc
							(start -0.3048 0.2032)
							(mid -0.275042 0.275042)
							(end -0.2032 0.3048)
						)
						(arc
							(start 0.2032 0.3048)
							(mid 0.275042 0.275042)
							(end 0.3048 0.2032)
						)
					)
					(width 0)
					(fill yes)
				)
			)
		)
	)
	(footprint ""
		(layer "F.Cu")
		(at 21.7932 -54.3052 -90)
		(property "Reference" "R17"
			(at 0 0 270)
			(layer "F.SilkS")
			(hide yes)
			(effects
				(font
					(size 1.27 1.27)
				)
			)
		)
		(property "Value" "100KR2J-4-GP"
			(at 0.064008 -3.993896 270)
			(unlocked yes)
			(layer "F.Fab")
			(hide yes)
			(effects
				(font
					(size 1.016 1.016)
					(thickness 0.1524)
				)
			)
		)
		(property "Device Type" "R402H15"
			(at 0.064008 -5.517896 270)
			(unlocked yes)
			(layer "F.Fab")
			(hide yes)
			(effects
				(font
					(size 1.016 1.016)
					(thickness 0.1524)
				)
			)
		)
		(duplicate_pad_numbers_are_jumpers no)
		(fp_line
			(start -0.508 -0.9398)
			(end -0.508 0.9398)
			(stroke
				(width 0.1524)
				(type default)
			)
			(layer "F.SilkS")
		)
		(fp_line
			(start 0.508 -0.9398)
			(end -0.508 -0.9398)
			(stroke
				(width 0.1524)
				(type default)
			)
			(layer "F.SilkS")
		)
		(fp_rect
			(start -0.508 0.9398)
			(end 0.508 -0.9398)
			(stroke
				(width 0)
				(type default)
			)
			(fill no)
			(layer "F.CrtYd")
		)
		(fp_rect
			(start -0.508 0.9398)
			(end 0.508 -0.9398)
			(stroke
				(width 0)
				(type default)
			)
			(fill no)
			(layer "F.Fab")
		)
		(pad "1" smd custom
			(at 0 -0.4445 270)
			(size 0.1397 0.1397)
			(layers "F.Cu" "F.Mask" "F.Paste")
			(net "MB0_VCAP_R")
			(options
				(clearance outline)
				(anchor circle)
			)
			(primitives
				(gr_poly
					(pts
						(arc
							(start -0.1778 -0.2794)
							(mid -0.249642 -0.249642)
							(end -0.2794 -0.1778)
						)
						(arc
							(start -0.2794 0.1778)
							(mid -0.249642 0.249642)
							(end -0.1778 0.2794)
						)
						(arc
							(start 0.1778 0.2794)
							(mid 0.249642 0.249642)
							(end 0.2794 0.1778)
						)
						(arc
							(start 0.2794 -0.1778)
							(mid 0.249642 -0.249642)
							(end 0.1778 -0.2794)
						)
					)
					(width 0)
					(fill yes)
				)
			)
		)
		(pad "2" smd custom
			(at 0 0.4445 270)
			(size 0.1397 0.1397)
			(layers "F.Cu" "F.Mask" "F.Paste")
			(net "MB0_ISET_R")
			(options
				(clearance outline)
				(anchor circle)
			)
			(primitives
				(gr_poly
					(pts
						(arc
							(start -0.1778 -0.2794)
							(mid -0.249642 -0.249642)
							(end -0.2794 -0.1778)
						)
						(arc
							(start -0.2794 0.1778)
							(mid -0.249642 0.249642)
							(end -0.1778 0.2794)
						)
						(arc
							(start 0.1778 0.2794)
							(mid 0.249642 0.249642)
							(end 0.2794 0.1778)
						)
						(arc
							(start 0.2794 -0.1778)
							(mid 0.249642 -0.249642)
							(end 0.1778 -0.2794)
						)
					)
					(width 0)
					(fill yes)
				)
			)
		)
	)
	(footprint ""
		(layer "F.Cu")
		(at 191.035432 -39.1414 -90)
		(property "Reference" "R179"
			(at 0 0 270)
			(layer "F.SilkS")
			(hide yes)
			(effects
				(font
					(size 1.27 1.27)
				)
			)
		)
		(property "Value" "2K2R2F-GP"
			(at 0.064008 -3.993896 270)
			(unlocked yes)
			(layer "F.Fab")
			(hide yes)
			(effects
				(font
					(size 1.016 1.016)
					(thickness 0.1524)
				)
			)
		)
		(property "Device Type" "R402H16"
			(at 0.064008 -5.517896 270)
			(unlocked yes)
			(layer "F.Fab")
			(hide yes)
			(effects
				(font
					(size 1.016 1.016)
					(thickness 0.1524)
				)
			)
		)
		(duplicate_pad_numbers_are_jumpers no)
		(fp_line
			(start -0.508 -0.9398)
			(end -0.508 0.9398)
			(stroke
				(width 0.1524)
				(type default)
			)
			(layer "F.SilkS")
		)
		(fp_line
			(start 0.508 -0.9398)
			(end -0.508 -0.9398)
			(stroke
				(width 0.1524)
				(type default)
			)
			(layer "F.SilkS")
		)
		(fp_rect
			(start -0.508 0.9398)
			(end 0.508 -0.9398)
			(stroke
				(width 0)
				(type default)
			)
			(fill no)
			(layer "F.CrtYd")
		)
		(fp_rect
			(start -0.508 0.9398)
			(end 0.508 -0.9398)
			(stroke
				(width 0)
				(type default)
			)
			(fill no)
			(layer "F.Fab")
		)
		(pad "1" smd custom
			(at 0 -0.4445 270)
			(size 0.1397 0.1397)
			(layers "F.Cu" "F.Mask" "F.Paste")
			(net "P1V8_C")
			(options
				(clearance outline)
				(anchor circle)
			)
			(primitives
				(gr_poly
					(pts
						(arc
							(start -0.1778 -0.2794)
							(mid -0.249642 -0.249642)
							(end -0.2794 -0.1778)
						)
						(arc
							(start -0.2794 0.1778)
							(mid -0.249642 0.249642)
							(end -0.1778 0.2794)
						)
						(arc
							(start 0.1778 0.2794)
							(mid 0.249642 0.249642)
							(end 0.2794 0.1778)
						)
						(arc
							(start 0.2794 -0.1778)
							(mid 0.249642 -0.249642)
							(end 0.1778 -0.2794)
						)
					)
					(width 0)
					(fill yes)
				)
			)
		)
		(pad "2" smd custom
			(at 0 0.4445 270)
			(size 0.1397 0.1397)
			(layers "F.Cu" "F.Mask" "F.Paste")
			(net "SBL_SCL")
			(options
				(clearance outline)
				(anchor circle)
			)
			(primitives
				(gr_poly
					(pts
						(arc
							(start -0.1778 -0.2794)
							(mid -0.249642 -0.249642)
							(end -0.2794 -0.1778)
						)
						(arc
							(start -0.2794 0.1778)
							(mid -0.249642 0.249642)
							(end -0.1778 0.2794)
						)
						(arc
							(start 0.1778 0.2794)
							(mid 0.249642 0.249642)
							(end 0.2794 0.1778)
						)
						(arc
							(start 0.2794 -0.1778)
							(mid 0.249642 -0.249642)
							(end 0.1778 -0.2794)
						)
					)
					(width 0)
					(fill yes)
				)
			)
		)
	)
)
